# S9S_MB_2U (Grand Teton) — schematic netlist excerpt (pin names and nets, part order shuffled) for the footprints in the layout excerpt that follows; sources: Cadence DE-HDL packaged netlist, KiCad conversion of 03242023_DA0F0TMBIJ0_F0T_Motherboard_J_brd_V01_OCP.brd

PR586  Q_RES  100 1% CHIP  pkg 0402LF  page 266 : A = VSENSE_PVCCFA_EHV_FIVRA_CPU0_DN ; B = GND
C2385  Q_CAP  100NF 50V 10% EMPTY  pkg C0402  page 307 : A = DSW_PWROK_P2V5_COMP ; B = GND

(kicad_pcb
	(version 20260206)
	(generator "pcbnew")
	(generator_version "10.0")
	(general
		(thickness 1.6)
		(legacy_teardrops no)
	)
	(paper "A4")
	(title_block
		(title "03242023_DA0F0TMBIJ0_F0T_Motherboard_J_brd_V01_OCP.brd")
		(comment 1 "Grand Teton / footprints 1156-1157 of 6105")
	)
	(layers
		(0 "F.Cu" signal "TOP")
		(4 "In1.Cu" signal "GND")
		(6 "In2.Cu" signal "IN1")
		(8 "In3.Cu" signal "GND1")
		(10 "In4.Cu" signal "IN2")
		(12 "In5.Cu" signal "GND2")
		(14 "In6.Cu" signal "IN3")
		(16 "In7.Cu" signal "GND3")
		(18 "In8.Cu" signal "VCC")
		(20 "In9.Cu" signal "VCC1")
		(22 "In10.Cu" signal "GND4")
		(24 "In11.Cu" signal "IN4")
		(26 "In12.Cu" signal "GND5")
		(28 "In13.Cu" signal "IN5")
		(30 "In14.Cu" signal "GND6")
		(32 "In15.Cu" signal "IN6")
		(34 "In16.Cu" signal "GND7")
		(2 "B.Cu" signal "BOTTOM")
		(9 "F.Adhes" user "F.Adhesive")
		(11 "B.Adhes" user "B.Adhesive")
		(13 "F.Paste" user "Package Geometry/Pastemask Top")
		(15 "B.Paste" user "Package Geometry/Pastemask Bottom")
		(5 "F.SilkS" user "Ref Des/Silkscreen Top")
		(7 "B.SilkS" user "Ref Des/Silkscreen Bottom")
		(1 "F.Mask" user "Board Geometry/Soldermask Top")
		(3 "B.Mask" user "Board Geometry/Soldermask Bottom")
		(17 "Dwgs.User" user "User.Drawings")
		(19 "Cmts.User" user "User.Comments")
		(21 "Eco1.User" user "User.Eco1")
		(23 "Eco2.User" user "User.Eco2")
		(25 "Edge.Cuts" user "Board Geometry/Outline")
		(27 "Margin" user)
		(31 "F.CrtYd" user "Package Geometry/Place Bound Top")
		(29 "B.CrtYd" user "Package Geometry/Place Bound Bottom")
		(35 "F.Fab" user "Ref Des/Assembly Top")
		(33 "B.Fab" user "Ref Des/Assembly Bottom")
	)
	(footprint ""
		(layer "F.Cu")
		(at 307.3908 -23.7744 180)
		(property "Reference" "C2385"
			(at 0 0 180)
			(layer "F.SilkS")
			(hide yes)
			(effects
				(font
					(size 1.27 1.27)
				)
			)
		)
		(property "Value" ""
			(at 0 0 180)
			(layer "F.Fab")
			(effects
				(font
					(size 1.27 1.27)
				)
			)
		)
		(duplicate_pad_numbers_are_jumpers no)
		(fp_line
			(start 0.7874 0.4064)
			(end -0.7874 0.4064)
			(stroke
				(width 0.1524)
				(type default)
			)
			(layer "F.SilkS")
		)
		(fp_line
			(start 0.7874 -0.4064)
			(end 0.7874 0.4064)
			(stroke
				(width 0.1524)
				(type default)
			)
			(layer "F.SilkS")
		)
		(fp_line
			(start -0.7874 0.4064)
			(end -0.7874 -0.4064)
			(stroke
				(width 0.1524)
				(type default)
			)
			(layer "F.SilkS")
		)
		(fp_line
			(start -0.7874 -0.4064)
			(end 0.7874 -0.4064)
			(stroke
				(width 0.1524)
				(type default)
			)
			(layer "F.SilkS")
		)
		(fp_line
			(start 0.67945 0.3048)
			(end 0.120396 0.3048)
			(stroke
				(width 0.1)
				(type default)
			)
			(layer "F.Fab")
		)
		(fp_line
			(start 0.67945 -0.3048)
			(end 0.67945 0.3048)
			(stroke
				(width 0.1)
				(type default)
			)
			(layer "F.Fab")
		)
		(fp_line
			(start 0.12065 -0.2794)
			(end 0.12065 -0.3048)
			(stroke
				(width 0.1)
				(type default)
			)
			(layer "F.Fab")
		)
		(fp_line
			(start 0.12065 -0.3048)
			(end 0.67945 -0.3048)
			(stroke
				(width 0.1)
				(type default)
			)
			(layer "F.Fab")
		)
		(fp_line
			(start 0.120396 0.3048)
			(end 0.120396 0.2794)
			(stroke
				(width 0.1)
				(type default)
			)
			(layer "F.Fab")
		)
		(fp_line
			(start 0.120396 0.2794)
			(end -0.12065 0.2794)
			(stroke
				(width 0.1)
				(type default)
			)
			(layer "F.Fab")
		)
		(fp_line
			(start -0.12065 0.3048)
			(end -0.67945 0.3048)
			(stroke
				(width 0.1)
				(type default)
			)
			(layer "F.Fab")
		)
		(fp_line
			(start -0.12065 0.2794)
			(end -0.12065 0.3048)
			(stroke
				(width 0.1)
				(type default)
			)
			(layer "F.Fab")
		)
		(fp_line
			(start -0.12065 -0.2794)
			(end 0.12065 -0.2794)
			(stroke
				(width 0.1)
				(type default)
			)
			(layer "F.Fab")
		)
		(fp_line
			(start -0.12065 -0.305054)
			(end -0.12065 -0.2794)
			(stroke
				(width 0.1)
				(type default)
			)
			(layer "F.Fab")
		)
		(fp_line
			(start -0.67945 0.3048)
			(end -0.67945 -0.305054)
			(stroke
				(width 0.1)
				(type default)
			)
			(layer "F.Fab")
		)
		(fp_line
			(start -0.67945 -0.305054)
			(end -0.12065 -0.305054)
			(stroke
				(width 0.1)
				(type default)
			)
			(layer "F.Fab")
		)
		(pad "1" smd circle
			(at -0.40005 0 180)
			(size 0 0)
			(layers "F.Cu" "F.Mask" "F.Paste")
			(net "DSW_PWROK_P2V5_COMP")
		)
		(pad "2" smd circle
			(at 0.40005 0 180)
			(size 0 0)
			(layers "F.Cu" "F.Mask" "F.Paste")
			(net "GND")
		)
	)
	(footprint ""
		(layer "F.Cu")
		(at 303.65573 -345.347544 180)
		(property "Reference" "PR586"
			(at 0 0 180)
			(layer "F.SilkS")
			(hide yes)
			(effects
				(font
					(size 1.27 1.27)
				)
			)
		)
		(property "Value" ""
			(at 0 0 180)
			(layer "F.Fab")
			(effects
				(font
					(size 1.27 1.27)
				)
			)
		)
		(duplicate_pad_numbers_are_jumpers no)
		(fp_line
			(start 0.7874 0.4064)
			(end -0.7874 0.4064)
			(stroke
				(width 0.1524)
				(type default)
			)
			(layer "F.SilkS")
		)
		(fp_line
			(start 0.7874 -0.4064)
			(end 0.7874 0.4064)
			(stroke
				(width 0.1524)
				(type default)
			)
			(layer "F.SilkS")
		)
		(fp_line
			(start -0.7874 0.4064)
			(end -0.7874 -0.4064)
			(stroke
				(width 0.1524)
				(type default)
			)
			(layer "F.SilkS")
		)
		(fp_line
			(start -0.7874 -0.4064)
			(end 0.7874 -0.4064)
			(stroke
				(width 0.1524)
				(type default)
			)
			(layer "F.SilkS")
		)
		(fp_line
			(start 0.67945 0.3048)
			(end 0.120396 0.3048)
			(stroke
				(width 0.1)
				(type default)
			)
			(layer "F.Fab")
		)
		(fp_line
			(start 0.67945 -0.3048)
			(end 0.67945 0.3048)
			(stroke
				(width 0.1)
				(type default)
			)
			(layer "F.Fab")
		)
		(fp_line
			(start 0.12065 -0.2794)
			(end 0.12065 -0.3048)
			(stroke
				(width 0.1)
				(type default)
			)
			(layer "F.Fab")
		)
		(fp_line
			(start 0.12065 -0.3048)
			(end 0.67945 -0.3048)
			(stroke
				(width 0.1)
				(type default)
			)
			(layer "F.Fab")
		)
		(fp_line
			(start 0.120396 0.3048)
			(end 0.120396 0.2794)
			(stroke
				(width 0.1)
				(type default)
			)
			(layer "F.Fab")
		)
		(fp_line
			(start 0.120396 0.2794)
			(end -0.12065 0.2794)
			(stroke
				(width 0.1)
				(type default)
			)
			(layer "F.Fab")
		)
		(fp_line
			(start -0.12065 0.3048)
			(end -0.67945 0.3048)
			(stroke
				(width 0.1)
				(type default)
			)
			(layer "F.Fab")
		)
		(fp_line
			(start -0.12065 0.2794)
			(end -0.12065 0.3048)
			(stroke
				(width 0.1)
				(type default)
			)
			(layer "F.Fab")
		)
		(fp_line
			(start -0.12065 -0.2794)
			(end 0.12065 -0.2794)
			(stroke
				(width 0.1)
				(type default)
			)
			(layer "F.Fab")
		)
		(fp_line
			(start -0.12065 -0.305054)
			(end -0.12065 -0.2794)
			(stroke
				(width 0.1)
				(type default)
			)
			(layer "F.Fab")
		)
		(fp_line
			(start -0.67945 0.3048)
			(end -0.67945 -0.305054)
			(stroke
				(width 0.1)
				(type default)
			)
			(layer "F.Fab")
		)
		(fp_line
			(start -0.67945 -0.305054)
			(end -0.12065 -0.305054)
			(stroke
				(width 0.1)
				(type default)
			)
			(layer "F.Fab")
		)
		(pad "1" smd circle
			(at -0.40005 0 180)
			(size 0 0)
			(layers "F.Cu" "F.Mask" "F.Paste")
			(net "VSENSE_PVCCFA_EHV_FIVRA_CPU0_DN")
		)
		(pad "2" smd circle
			(at 0.40005 0 180)
			(size 0 0)
			(layers "F.Cu" "F.Mask" "F.Paste")
			(net "GND")
		)
	)
)
